# BASEBOARD_FAB2 (Tioga Pass) — schematic netlist excerpt (pin names and nets, part order shuffled) for the footprints in the layout excerpt that follows; sources: Cadence DE-HDL packaged netlist, KiCad conversion of Wiwynn_Tioga_Pass_MB.brd

EU25F2  RT9059  IC  pkg DFN  page 239
  VOUT(0)  = P2V5_AUX_BMC
  VOUT(1)  = P2V5_AUX_BMC
  VOUT(2)  = P2V5_AUX_BMC
  ADJ_NC  = VR_P2V5_BMC_STBY_FB
  PGOOD  = PWRGD_P2V5_BMC_STBY_R
  EN  = PWRGD_P3V3_STBY
  VIN(0)  = P3V3_STBY
  VIN(1)  = P3V3_STBY
  VIN(2)  = P3V3_STBY
  VDD  = P3V3_STBY
  GND  = GND

C2D12  CAP_A  22.0UF 4V 20% X6S  pkg 0603V  page 76 : A = PVCCIN_CPU1 ; B = GND
C9E10  CAP  10UF 6.3V 20% X6S  pkg 0603  page 238 : A = P1V15_AUX_BMC ; B = GND

(kicad_pcb
	(version 20260206)
	(generator "pcbnew")
	(generator_version "10.0")
	(general
		(thickness 1.6)
		(legacy_teardrops no)
	)
	(paper "A4")
	(title_block
		(title "Wiwynn_Tioga_Pass_MB.brd")
		(comment 1 "Tioga Pass / footprints 501-503 of 4770")
	)
	(layers
		(0 "F.Cu" signal "TOP")
		(4 "In1.Cu" signal "L2GND")
		(6 "In2.Cu" signal "L3")
		(8 "In3.Cu" signal "L4GND")
		(10 "In4.Cu" signal "L5")
		(12 "In5.Cu" signal "L6GND")
		(14 "In6.Cu" signal "L7VCC")
		(16 "In7.Cu" signal "L8VCC")
		(18 "In8.Cu" signal "L9GND")
		(20 "In9.Cu" signal "L10")
		(22 "In10.Cu" signal "L11GND")
		(24 "In11.Cu" signal "L12")
		(26 "In12.Cu" signal "L13GND")
		(2 "B.Cu" signal "BOTTOM")
		(9 "F.Adhes" user "F.Adhesive")
		(11 "B.Adhes" user "B.Adhesive")
		(13 "F.Paste" user "Package Geometry/Pastemask Top")
		(15 "B.Paste" user "Package Geometry/Pastemask Bottom")
		(5 "F.SilkS" user "Ref Des/Silkscreen Top")
		(7 "B.SilkS" user "Ref Des/Silkscreen Bottom")
		(1 "F.Mask" user "Board Geometry/Soldermask Top")
		(3 "B.Mask" user "Board Geometry/Soldermask Bottom")
		(17 "Dwgs.User" user "User.Drawings")
		(19 "Cmts.User" user "User.Comments")
		(21 "Eco1.User" user "User.Eco1")
		(23 "Eco2.User" user "User.Eco2")
		(25 "Edge.Cuts" user "Board Geometry/Outline")
		(27 "Margin" user)
		(31 "F.CrtYd" user "Package Geometry/Place Bound Top")
		(29 "B.CrtYd" user "Package Geometry/Place Bound Bottom")
		(35 "F.Fab" user "Ref Des/Assembly Top")
		(33 "B.Fab" user "Ref Des/Assembly Bottom")
	)
	(footprint ""
		(layer "F.Cu")
		(at 452.767192 -23.605998)
		(property "Reference" "EU25F2"
			(at -0.256286 -1.613408 0)
			(unlocked yes)
			(layer "F.SilkS")
			(effects
				(font
					(size 1.27 0.964946)
					(thickness 0.000001)
				)
				(justify left)
			)
		)
		(property "Value" ""
			(at 0 0 0)
			(layer "F.Fab")
			(effects
				(font
					(size 1.27 1.27)
				)
			)
		)
		(duplicate_pad_numbers_are_jumpers no)
		(fp_circle
			(center -0.835152 -0.417322)
			(end -0.708406 -0.417322)
			(stroke
				(width 0.254)
				(type default)
			)
			(fill no)
			(layer "F.SilkS")
		)
		(fp_poly
			(pts
				(xy -0.064516 -1.0922) (xy -0.064516 -0.3302) (xy 0.697484 -1.0922)
			)
			(stroke
				(width 0)
				(type default)
			)
			(fill yes)
			(layer "F.SilkS")
		)
		(fp_rect
			(start 0.597408 2.295398)
			(end 2.273808 -0.295402)
			(stroke
				(width 0)
				(type default)
			)
			(fill yes)
			(layer "F.Paste")
		)
		(fp_rect
			(start -0.064516 2.500122)
			(end 2.935478 -0.500126)
			(stroke
				(width 0)
				(type default)
			)
			(fill no)
			(layer "F.CrtYd")
		)
		(fp_line
			(start -0.064516 -0.500126)
			(end 2.935478 -0.500126)
			(stroke
				(width 0.1)
				(type default)
			)
			(layer "F.Fab")
		)
		(fp_line
			(start -0.064516 2.500122)
			(end -0.064516 -0.500126)
			(stroke
				(width 0.1)
				(type default)
			)
			(layer "F.Fab")
		)
		(fp_line
			(start 2.935478 -0.500126)
			(end 2.935478 2.500122)
			(stroke
				(width 0.1)
				(type default)
			)
			(layer "F.Fab")
		)
		(fp_line
			(start 2.935478 2.500122)
			(end -0.064516 2.500122)
			(stroke
				(width 0.1)
				(type default)
			)
			(layer "F.Fab")
		)
		(fp_circle
			(center -0.835152 -0.417322)
			(end -0.708406 -0.417322)
			(stroke
				(width 0.254)
				(type default)
			)
			(fill no)
			(layer "F.Fab")
		)
		(pad "1" smd rect
			(at 0 0)
			(size 0.6858 0.3048)
			(layers "F.Cu" "F.Mask" "F.Paste")
			(net "P2V5_AUX_BMC")
		)
		(pad "2" smd rect
			(at 0 0.500126)
			(size 0.6858 0.3048)
			(layers "F.Cu" "F.Mask" "F.Paste")
			(net "P2V5_AUX_BMC")
		)
		(pad "3" smd rect
			(at 0 0.999998)
			(size 0.6858 0.3048)
			(layers "F.Cu" "F.Mask" "F.Paste")
			(net "P2V5_AUX_BMC")
		)
		(pad "4" smd rect
			(at 0 1.500124)
			(size 0.6858 0.3048)
			(layers "F.Cu" "F.Mask" "F.Paste")
			(net "VR_P2V5_BMC_STBY_FB")
		)
		(pad "5" smd rect
			(at 0 1.999996)
			(size 0.6858 0.3048)
			(layers "F.Cu" "F.Mask" "F.Paste")
			(net "PWRGD_P2V5_BMC_STBY_R")
		)
		(pad "6" smd rect
			(at 2.871216 1.999996)
			(size 0.6858 0.3048)
			(layers "F.Cu" "F.Mask" "F.Paste")
			(net "PWRGD_P3V3_STBY")
		)
		(pad "7" smd rect
			(at 2.871216 1.500124)
			(size 0.6858 0.3048)
			(layers "F.Cu" "F.Mask" "F.Paste")
			(net "P3V3_STBY")
		)
		(pad "8" smd rect
			(at 2.871216 0.999998)
			(size 0.6858 0.3048)
			(layers "F.Cu" "F.Mask" "F.Paste")
			(net "P3V3_STBY")
		)
		(pad "9" smd rect
			(at 2.871216 0.500126)
			(size 0.6858 0.3048)
			(layers "F.Cu" "F.Mask" "F.Paste")
			(net "P3V3_STBY")
		)
		(pad "10" smd rect
			(at 2.871216 0)
			(size 0.6858 0.3048)
			(layers "F.Cu" "F.Mask" "F.Paste")
			(net "P3V3_STBY")
		)
		(pad "11" smd rect
			(at 1.435608 0.999998)
			(size 1.6764 2.5908)
			(layers "F.Cu" "F.Mask" "F.Paste")
			(net "GND")
		)
	)
	(footprint ""
		(layer "F.Cu")
		(at 96.949768 -79.6036 180)
		(property "Reference" "C2D12"
			(at 0 0 180)
			(layer "F.SilkS")
			(hide yes)
			(effects
				(font
					(size 1.27 1.27)
				)
			)
		)
		(property "Value" ""
			(at 0 0 180)
			(layer "F.Fab")
			(effects
				(font
					(size 1.27 1.27)
				)
			)
		)
		(duplicate_pad_numbers_are_jumpers no)
		(fp_poly
			(pts
				(xy -0.4953 -0.2032) (xy 0.4953 -0.2032) (xy 0.4953 1.6002) (xy -0.4953 1.6002)
			)
			(stroke
				(width 0)
				(type default)
			)
			(fill no)
			(layer "F.CrtYd")
		)
		(fp_line
			(start 0.4953 1.6002)
			(end -0.4953 1.6002)
			(stroke
				(width 0.1)
				(type default)
			)
			(layer "F.Fab")
		)
		(fp_line
			(start 0.4953 -0.2032)
			(end 0.4953 1.6002)
			(stroke
				(width 0.1)
				(type default)
			)
			(layer "F.Fab")
		)
		(fp_line
			(start -0.4953 1.6002)
			(end -0.4953 -0.2032)
			(stroke
				(width 0.1)
				(type default)
			)
			(layer "F.Fab")
		)
		(fp_line
			(start -0.4953 -0.2032)
			(end 0.4953 -0.2032)
			(stroke
				(width 0.1)
				(type default)
			)
			(layer "F.Fab")
		)
		(pad "1" smd rect
			(at 0 0 180)
			(size 0.762 0.889)
			(layers "F.Cu" "F.Mask" "F.Paste")
			(net "PVCCIN_CPU1")
		)
		(pad "2" smd rect
			(at 0 1.397 180)
			(size 0.762 0.889)
			(layers "F.Cu" "F.Mask" "F.Paste")
			(net "GND")
		)
		(zone
			(layer "F.Cu")
			(hatch none 0.5)
			(connect_pads
				(clearance 0)
			)
			(min_thickness 0.25)
			(keepout
				(tracks not_allowed)
				(vias allowed)
				(pads allowed)
				(copperpour not_allowed)
				(footprints allowed)
			)
			(placement
				(enabled no)
				(sheetname "")
			)
			(fill
				(thermal_gap 0.5)
				(thermal_bridge_width 0.5)
				(island_removal_mode 0)
			)
			(polygon
				(pts
					(xy 97.330768 -80.0481) (xy 96.568768 -80.0481) (xy 96.568768 -80.5561) (xy 97.330768 -80.5561)
				)
			)
		)
	)
	(footprint ""
		(layer "F.Cu")
		(at 457.923392 -42.401998 -90)
		(property "Reference" "C9E10"
			(at 0 0 270)
			(layer "F.SilkS")
			(hide yes)
			(effects
				(font
					(size 1.27 1.27)
				)
			)
		)
		(property "Value" ""
			(at 0 0 270)
			(layer "F.Fab")
			(effects
				(font
					(size 1.27 1.27)
				)
			)
		)
		(duplicate_pad_numbers_are_jumpers no)
		(fp_poly
			(pts
				(xy -0.4953 -0.2032) (xy 0.4953 -0.2032) (xy 0.4953 1.6002) (xy -0.4953 1.6002)
			)
			(stroke
				(width 0)
				(type default)
			)
			(fill no)
			(layer "F.CrtYd")
		)
		(fp_line
			(start -0.4953 1.6002)
			(end -0.4953 -0.2032)
			(stroke
				(width 0.1)
				(type default)
			)
			(layer "F.Fab")
		)
		(fp_line
			(start 0.4953 1.6002)
			(end -0.4953 1.6002)
			(stroke
				(width 0.1)
				(type default)
			)
			(layer "F.Fab")
		)
		(fp_line
			(start -0.4953 -0.2032)
			(end 0.4953 -0.2032)
			(stroke
				(width 0.1)
				(type default)
			)
			(layer "F.Fab")
		)
		(fp_line
			(start 0.4953 -0.2032)
			(end 0.4953 1.6002)
			(stroke
				(width 0.1)
				(type default)
			)
			(layer "F.Fab")
		)
		(pad "1" smd rect
			(at 0 0 270)
			(size 0.762 0.889)
			(layers "F.Cu" "F.Mask" "F.Paste")
			(net "P1V15_AUX_BMC")
		)
		(pad "2" smd rect
			(at 0 1.397 270)
			(size 0.762 0.889)
			(layers "F.Cu" "F.Mask" "F.Paste")
			(net "GND")
		)
		(zone
			(layer "F.Cu")
			(hatch none 0.5)
			(connect_pads
				(clearance 0)
			)
			(min_thickness 0.25)
			(keepout
				(tracks not_allowed)
				(vias allowed)
				(pads allowed)
				(copperpour not_allowed)
				(footprints allowed)
			)
			(placement
				(enabled no)
				(sheetname "")
			)
			(fill
				(thermal_gap 0.5)
				(thermal_bridge_width 0.5)
				(island_removal_mode 0)
			)
			(polygon
				(pts
					(xy 457.478892 -42.782998) (xy 457.478892 -42.020998) (xy 456.970892 -42.020998) (xy 456.970892 -42.782998)
				)
			)
		)
	)
)
